(kicad_pcb
	(version 20260206)
	(generator "pcbnew")
	(generator_version "10.0")
	(general
		(thickness 1.6)
		(legacy_teardrops no)
	)
	(paper "A4")
	(title_block
		(title "peb — Lightning_PEB_BRD.brd")
		(comment 1 "Lightning (Wiwynn / Facebook NVMe JBOF) / footprints 2053-2060 of 2563")
	)
	(layers
		(0 "F.Cu" signal "TOP")
		(4 "In1.Cu" signal "L2GND")
		(6 "In2.Cu" signal "L3")
		(8 "In3.Cu" signal "L4VCC")
		(10 "In4.Cu" signal "L5VCC")
		(12 "In5.Cu" signal "L6")
		(14 "In6.Cu" signal "L7GND")
		(2 "B.Cu" signal "BOTTOM")
		(9 "F.Adhes" user "F.Adhesive")
		(11 "B.Adhes" user "B.Adhesive")
		(13 "F.Paste" user "Package Geometry/Pastemask Top")
		(15 "B.Paste" user "Package Geometry/Pastemask Bottom")
		(5 "F.SilkS" user "Ref Des/Silkscreen Top")
		(7 "B.SilkS" user "Ref Des/Silkscreen Bottom")
		(1 "F.Mask" user "Board Geometry/Soldermask Top")
		(3 "B.Mask" user "Board Geometry/Soldermask Bottom")
		(17 "Dwgs.User" user "User.Drawings")
		(19 "Cmts.User" user "User.Comments")
		(21 "Eco1.User" user "User.Eco1")
		(23 "Eco2.User" user "User.Eco2")
		(25 "Edge.Cuts" user "Board Geometry/Outline")
		(27 "Margin" user)
		(31 "F.CrtYd" user "Package Geometry/Place Bound Top")
		(29 "B.CrtYd" user "Package Geometry/Place Bound Bottom")
		(35 "F.Fab" user "Ref Des/Assembly Top")
		(33 "B.Fab" user "Ref Des/Assembly Bottom")
	)
	(footprint ""
		(layer "B.Cu")
		(at 240.538 -18.161)
		(property "Reference" "TP193"
			(at 0 0 0)
			(layer "B.SilkS")
			(hide yes)
			(effects
				(font
					(size 1.27 1.27)
				)
				(justify mirror)
			)
		)
		(property "Value" "TPAD28-2-GP"
			(at 0.0127 -1.6637 0)
			(unlocked yes)
			(layer "B.Fab")
			(hide yes)
			(effects
				(font
					(size 1.016 1.016)
					(thickness 0.1524)
				)
				(justify mirror)
			)
		)
		(property "Device Type" "TPAD28"
			(at 0.0127 -3.1877 0)
			(unlocked yes)
			(layer "B.Fab")
			(hide yes)
			(effects
				(font
					(size 1.016 1.016)
					(thickness 0.1524)
				)
				(justify mirror)
			)
		)
		(duplicate_pad_numbers_are_jumpers no)
		(fp_poly
			(pts
				(arc
					(start 0.3556 0)
					(mid -0.3556 0)
					(end 0.3556 0)
				)
			)
			(stroke
				(width 0)
				(type default)
			)
			(fill no)
			(layer "B.CrtYd")
		)
		(fp_poly
			(pts
				(arc
					(start 0.6096 0)
					(mid -0.6096 0)
					(end 0.6096 0)
				)
			)
			(stroke
				(width 0)
				(type default)
			)
			(fill no)
			(layer "B.Fab")
		)
		(pad "1" smd circle
			(at 0 0 180)
			(size 0.7112 0.7112)
			(layers "B.Cu" "B.Mask" "B.Paste")
			(net "LBI_DATA_0")
		)
	)
	(footprint ""
		(layer "B.Cu")
		(at 239.1664 -47.032672 90)
		(property "Reference" "C38"
			(at 0 0 90)
			(layer "B.SilkS")
			(hide yes)
			(effects
				(font
					(size 1.27 1.27)
				)
				(justify mirror)
			)
		)
		(property "Value" "SCD1U16V1KX-1-GP"
			(at 2.8321 -1.7399 90)
			(unlocked yes)
			(layer "B.Fab")
			(hide yes)
			(effects
				(font
					(size 1.016 1.016)
					(thickness 0.1524)
				)
				(justify mirror)
			)
		)
		(property "Device Type" "C0201H13"
			(at 2.8321 -3.2639 90)
			(unlocked yes)
			(layer "B.Fab")
			(hide yes)
			(effects
				(font
					(size 1.016 1.016)
					(thickness 0.1524)
				)
				(justify mirror)
			)
		)
		(duplicate_pad_numbers_are_jumpers no)
		(fp_rect
			(start 0.2794 0.6477)
			(end -0.2794 -0.6477)
			(stroke
				(width 0)
				(type default)
			)
			(fill no)
			(layer "B.CrtYd")
		)
		(fp_rect
			(start 0.2794 0.6477)
			(end -0.2794 -0.6477)
			(stroke
				(width 0)
				(type default)
			)
			(fill no)
			(layer "B.Fab")
		)
		(pad "1" smd custom
			(at 0 -0.2794 270)
			(size 0.0762 0.0762)
			(layers "B.Cu" "B.Mask" "B.Paste")
			(net "DUT_VDD")
			(options
				(clearance outline)
				(anchor circle)
			)
			(primitives
				(gr_poly
					(pts
						(arc
							(start 0.1524 0.127)
							(mid 0.137521 0.162921)
							(end 0.1016 0.1778)
						)
						(arc
							(start -0.1016 0.1778)
							(mid -0.137521 0.162921)
							(end -0.1524 0.127)
						)
						(arc
							(start -0.1524 -0.127)
							(mid -0.137521 -0.162921)
							(end -0.1016 -0.1778)
						)
						(arc
							(start 0.1016 -0.1778)
							(mid 0.137521 -0.162921)
							(end 0.1524 -0.127)
						)
					)
					(width 0)
					(fill yes)
				)
			)
		)
		(pad "2" smd custom
			(at 0 0.2794 270)
			(size 0.0762 0.0762)
			(layers "B.Cu" "B.Mask" "B.Paste")
			(net "GND")
			(options
				(clearance outline)
				(anchor circle)
			)
			(primitives
				(gr_poly
					(pts
						(arc
							(start 0.1524 0.127)
							(mid 0.137521 0.162921)
							(end 0.1016 0.1778)
						)
						(arc
							(start -0.1016 0.1778)
							(mid -0.137521 0.162921)
							(end -0.1524 0.127)
						)
						(arc
							(start -0.1524 -0.127)
							(mid -0.137521 -0.162921)
							(end -0.1016 -0.1778)
						)
						(arc
							(start 0.1016 -0.1778)
							(mid 0.137521 -0.162921)
							(end 0.1524 -0.127)
						)
					)
					(width 0)
					(fill yes)
				)
			)
		)
	)
	(footprint ""
		(layer "B.Cu")
		(at 242.443 -17.2466 -90)
		(property "Reference" "R4177"
			(at 0 0 90)
			(layer "B.SilkS")
			(hide yes)
			(effects
				(font
					(size 1.27 1.27)
				)
				(justify mirror)
			)
		)
		(property "Value" "4K7R2F-GP"
			(at -0.064008 -3.993896 270)
			(unlocked yes)
			(layer "B.Fab")
			(hide yes)
			(effects
				(font
					(size 1.016 1.016)
					(thickness 0.1524)
				)
				(justify mirror)
			)
		)
		(property "Device Type" "R402H16"
			(at -0.064008 -5.517896 270)
			(unlocked yes)
			(layer "B.Fab")
			(hide yes)
			(effects
				(font
					(size 1.016 1.016)
					(thickness 0.1524)
				)
				(justify mirror)
			)
		)
		(duplicate_pad_numbers_are_jumpers no)
		(fp_line
			(start -0.508 -0.9398)
			(end 0.508 -0.9398)
			(stroke
				(width 0.1524)
				(type default)
			)
			(layer "B.SilkS")
		)
		(fp_line
			(start 0.508 -0.9398)
			(end 0.508 0.9398)
			(stroke
				(width 0.1524)
				(type default)
			)
			(layer "B.SilkS")
		)
		(fp_rect
			(start 0.508 0.9398)
			(end -0.508 -0.9398)
			(stroke
				(width 0)
				(type default)
			)
			(fill no)
			(layer "B.CrtYd")
		)
		(fp_rect
			(start 0.508 0.9398)
			(end -0.508 -0.9398)
			(stroke
				(width 0)
				(type default)
			)
			(fill no)
			(layer "B.Fab")
		)
		(pad "1" smd custom
			(at 0 -0.4445 90)
			(size 0.1397 0.1397)
			(layers "B.Cu" "B.Mask" "B.Paste")
			(net "PM8536_HB")
			(options
				(clearance outline)
				(anchor circle)
			)
			(primitives
				(gr_poly
					(pts
						(arc
							(start -0.1778 0.2794)
							(mid -0.249642 0.249642)
							(end -0.2794 0.1778)
						)
						(arc
							(start -0.2794 -0.1778)
							(mid -0.249642 -0.249642)
							(end -0.1778 -0.2794)
						)
						(arc
							(start 0.1778 -0.2794)
							(mid 0.249642 -0.249642)
							(end 0.2794 -0.1778)
						)
						(arc
							(start 0.2794 0.1778)
							(mid 0.249642 0.249642)
							(end 0.1778 0.2794)
						)
					)
					(width 0)
					(fill yes)
				)
			)
		)
		(pad "2" smd custom
			(at 0 0.4445 90)
			(size 0.1397 0.1397)
			(layers "B.Cu" "B.Mask" "B.Paste")
			(net "P3V3_STBY")
			(options
				(clearance outline)
				(anchor circle)
			)
			(primitives
				(gr_poly
					(pts
						(arc
							(start -0.1778 0.2794)
							(mid -0.249642 0.249642)
							(end -0.2794 0.1778)
						)
						(arc
							(start -0.2794 -0.1778)
							(mid -0.249642 -0.249642)
							(end -0.1778 -0.2794)
						)
						(arc
							(start 0.1778 -0.2794)
							(mid 0.249642 -0.249642)
							(end 0.2794 -0.1778)
						)
						(arc
							(start 0.2794 0.1778)
							(mid 0.249642 0.249642)
							(end 0.1778 0.2794)
						)
					)
					(width 0)
					(fill yes)
				)
			)
		)
	)
	(footprint ""
		(layer "B.Cu")
		(at 24.13 -121.0056 -90)
		(property "Reference" "R554"
			(at 0 0 90)
			(layer "B.SilkS")
			(hide yes)
			(effects
				(font
					(size 1.27 1.27)
				)
				(justify mirror)
			)
		)
		(property "Value" "0R2J-2-GP"
			(at -0.064008 -3.993896 270)
			(unlocked yes)
			(layer "B.Fab")
			(hide yes)
			(effects
				(font
					(size 1.016 1.016)
					(thickness 0.1524)
				)
				(justify mirror)
			)
		)
		(property "Device Type" "R402H16"
			(at -0.064008 -5.517896 270)
			(unlocked yes)
			(layer "B.Fab")
			(hide yes)
			(effects
				(font
					(size 1.016 1.016)
					(thickness 0.1524)
				)
				(justify mirror)
			)
		)
		(duplicate_pad_numbers_are_jumpers no)
		(fp_line
			(start -0.508 -0.9398)
			(end 0.508 -0.9398)
			(stroke
				(width 0.1524)
				(type default)
			)
			(layer "B.SilkS")
		)
		(fp_line
			(start 0.508 -0.9398)
			(end 0.508 0.9398)
			(stroke
				(width 0.1524)
				(type default)
			)
			(layer "B.SilkS")
		)
		(fp_rect
			(start 0.508 0.9398)
			(end -0.508 -0.9398)
			(stroke
				(width 0)
				(type default)
			)
			(fill no)
			(layer "B.CrtYd")
		)
		(fp_rect
			(start 0.508 0.9398)
			(end -0.508 -0.9398)
			(stroke
				(width 0)
				(type default)
			)
			(fill no)
			(layer "B.Fab")
		)
		(pad "1" smd custom
			(at 0 -0.4445 90)
			(size 0.1397 0.1397)
			(layers "B.Cu" "B.Mask" "B.Paste")
			(net "FM_PCH_LAN1_DISABLE_N_R")
			(options
				(clearance outline)
				(anchor circle)
			)
			(primitives
				(gr_poly
					(pts
						(arc
							(start -0.1778 0.2794)
							(mid -0.249642 0.249642)
							(end -0.2794 0.1778)
						)
						(arc
							(start -0.2794 -0.1778)
							(mid -0.249642 -0.249642)
							(end -0.1778 -0.2794)
						)
						(arc
							(start 0.1778 -0.2794)
							(mid 0.249642 -0.249642)
							(end 0.2794 -0.1778)
						)
						(arc
							(start 0.2794 0.1778)
							(mid 0.249642 0.249642)
							(end 0.1778 0.2794)
						)
					)
					(width 0)
					(fill yes)
				)
			)
		)
		(pad "2" smd custom
			(at 0 0.4445 90)
			(size 0.1397 0.1397)
			(layers "B.Cu" "B.Mask" "B.Paste")
			(net "FM_PCH_LAN1_DISABLE_N")
			(options
				(clearance outline)
				(anchor circle)
			)
			(primitives
				(gr_poly
					(pts
						(arc
							(start -0.1778 0.2794)
							(mid -0.249642 0.249642)
							(end -0.2794 0.1778)
						)
						(arc
							(start -0.2794 -0.1778)
							(mid -0.249642 -0.249642)
							(end -0.1778 -0.2794)
						)
						(arc
							(start 0.1778 -0.2794)
							(mid 0.249642 -0.249642)
							(end 0.2794 -0.1778)
						)
						(arc
							(start 0.2794 0.1778)
							(mid 0.249642 0.249642)
							(end 0.1778 0.2794)
						)
					)
					(width 0)
					(fill yes)
				)
			)
		)
	)
	(footprint ""
		(layer "B.Cu")
		(at 269.150084 -17.37106 90)
		(property "Reference" "R2976"
			(at 0 0 90)
			(layer "B.SilkS")
			(hide yes)
			(effects
				(font
					(size 1.27 1.27)
				)
				(justify mirror)
			)
		)
		(property "Value" "0R2J-2-GP"
			(at -0.064008 -3.993896 90)
			(unlocked yes)
			(layer "B.Fab")
			(hide yes)
			(effects
				(font
					(size 1.016 1.016)
					(thickness 0.1524)
				)
				(justify mirror)
			)
		)
		(property "Device Type" "R402H16"
			(at -0.064008 -5.517896 90)
			(unlocked yes)
			(layer "B.Fab")
			(hide yes)
			(effects
				(font
					(size 1.016 1.016)
					(thickness 0.1524)
				)
				(justify mirror)
			)
		)
		(duplicate_pad_numbers_are_jumpers no)
		(fp_line
			(start 0.508 -0.9398)
			(end 0.508 0.9398)
			(stroke
				(width 0.1524)
				(type default)
			)
			(layer "B.SilkS")
		)
		(fp_line
			(start -0.508 -0.9398)
			(end 0.508 -0.9398)
			(stroke
				(width 0.1524)
				(type default)
			)
			(layer "B.SilkS")
		)
		(fp_rect
			(start 0.508 0.9398)
			(end -0.508 -0.9398)
			(stroke
				(width 0)
				(type default)
			)
			(fill no)
			(layer "B.CrtYd")
		)
		(fp_rect
			(start 0.508 0.9398)
			(end -0.508 -0.9398)
			(stroke
				(width 0)
				(type default)
			)
			(fill no)
			(layer "B.Fab")
		)
		(pad "1" smd custom
			(at 0 -0.4445 270)
			(size 0.1397 0.1397)
			(layers "B.Cu" "B.Mask" "B.Paste")
			(net "USB_P4_DP_BMC")
			(options
				(clearance outline)
				(anchor circle)
			)
			(primitives
				(gr_poly
					(pts
						(arc
							(start -0.1778 0.2794)
							(mid -0.249642 0.249642)
							(end -0.2794 0.1778)
						)
						(arc
							(start -0.2794 -0.1778)
							(mid -0.249642 -0.249642)
							(end -0.1778 -0.2794)
						)
						(arc
							(start 0.1778 -0.2794)
							(mid 0.249642 -0.249642)
							(end 0.2794 -0.1778)
						)
						(arc
							(start 0.2794 0.1778)
							(mid 0.249642 0.249642)
							(end 0.1778 0.2794)
						)
					)
					(width 0)
					(fill yes)
				)
			)
		)
		(pad "2" smd custom
			(at 0 0.4445 270)
			(size 0.1397 0.1397)
			(layers "B.Cu" "B.Mask" "B.Paste")
			(net "8644_USB_DP5")
			(options
				(clearance outline)
				(anchor circle)
			)
			(primitives
				(gr_poly
					(pts
						(arc
							(start -0.1778 0.2794)
							(mid -0.249642 0.249642)
							(end -0.2794 0.1778)
						)
						(arc
							(start -0.2794 -0.1778)
							(mid -0.249642 -0.249642)
							(end -0.1778 -0.2794)
						)
						(arc
							(start 0.1778 -0.2794)
							(mid 0.249642 -0.249642)
							(end 0.2794 -0.1778)
						)
						(arc
							(start 0.2794 0.1778)
							(mid 0.249642 0.249642)
							(end 0.1778 0.2794)
						)
					)
					(width 0)
					(fill yes)
				)
			)
		)
	)
	(footprint ""
		(layer "B.Cu")
		(at 35.687 -132.588 90)
		(property "Reference" "C207"
			(at 0 0 90)
			(layer "B.SilkS")
			(hide yes)
			(effects
				(font
					(size 1.27 1.27)
				)
				(justify mirror)
			)
		)
		(property "Value" "SC1U10V2KX-4-GP"
			(at -1.1811 -2.7051 90)
			(unlocked yes)
			(layer "B.Fab")
			(hide yes)
			(effects
				(font
					(size 1.016 1.016)
					(thickness 0.1524)
				)
				(justify mirror)
			)
		)
		(property "Device Type" "C402H22"
			(at -1.1811 -4.2291 90)
			(unlocked yes)
			(layer "B.Fab")
			(hide yes)
			(effects
				(font
					(size 1.016 1.016)
					(thickness 0.1524)
				)
				(justify mirror)
			)
		)
		(duplicate_pad_numbers_are_jumpers no)
		(fp_rect
			(start 0.4318 0.9525)
			(end -0.4318 -0.9525)
			(stroke
				(width 0)
				(type default)
			)
			(fill no)
			(layer "B.CrtYd")
		)
		(fp_rect
			(start 0.4318 0.9525)
			(end -0.4318 -0.9525)
			(stroke
				(width 0)
				(type default)
			)
			(fill no)
			(layer "B.Fab")
		)
		(pad "1" smd custom
			(at 0 -0.4445 270)
			(size 0.1524 0.1524)
			(layers "B.Cu" "B.Mask" "B.Paste")
			(net "P1V26_STBY")
			(options
				(clearance outline)
				(anchor circle)
			)
			(primitives
				(gr_poly
					(pts
						(arc
							(start 0.3048 0.2032)
							(mid 0.275042 0.275042)
							(end 0.2032 0.3048)
						)
						(arc
							(start -0.2032 0.3048)
							(mid -0.275042 0.275042)
							(end -0.3048 0.2032)
						)
						(arc
							(start -0.3048 -0.2032)
							(mid -0.275042 -0.275042)
							(end -0.2032 -0.3048)
						)
						(arc
							(start 0.2032 -0.3048)
							(mid 0.275042 -0.275042)
							(end 0.3048 -0.2032)
						)
					)
					(width 0)
					(fill yes)
				)
			)
		)
		(pad "2" smd custom
			(at 0 0.4445 270)
			(size 0.1524 0.1524)
			(layers "B.Cu" "B.Mask" "B.Paste")
			(net "GND")
			(options
				(clearance outline)
				(anchor circle)
			)
			(primitives
				(gr_poly
					(pts
						(arc
							(start 0.3048 0.2032)
							(mid 0.275042 0.275042)
							(end 0.2032 0.3048)
						)
						(arc
							(start -0.2032 0.3048)
							(mid -0.275042 0.275042)
							(end -0.3048 0.2032)
						)
						(arc
							(start -0.3048 -0.2032)
							(mid -0.275042 -0.275042)
							(end -0.2032 -0.3048)
						)
						(arc
							(start 0.2032 -0.3048)
							(mid 0.275042 -0.275042)
							(end 0.3048 -0.2032)
						)
					)
					(width 0)
					(fill yes)
				)
			)
		)
	)
	(footprint ""
		(layer "B.Cu")
		(at 126.492 -203.835)
		(property "Reference" "R144"
			(at 0 0 0)
			(layer "B.SilkS")
			(hide yes)
			(effects
				(font
					(size 1.27 1.27)
				)
				(justify mirror)
			)
		)
		(property "Value" "4K7R2F-GP"
			(at -0.064008 -3.993896 0)
			(unlocked yes)
			(layer "B.Fab")
			(hide yes)
			(effects
				(font
					(size 1.016 1.016)
					(thickness 0.1524)
				)
				(justify mirror)
			)
		)
		(property "Device Type" "R402H16"
			(at -0.064008 -5.517896 0)
			(unlocked yes)
			(layer "B.Fab")
			(hide yes)
			(effects
				(font
					(size 1.016 1.016)
					(thickness 0.1524)
				)
				(justify mirror)
			)
		)
		(duplicate_pad_numbers_are_jumpers no)
		(fp_line
			(start -0.508 -0.9398)
			(end 0.508 -0.9398)
			(stroke
				(width 0.1524)
				(type default)
			)
			(layer "B.SilkS")
		)
		(fp_line
			(start 0.508 -0.9398)
			(end 0.508 0.9398)
			(stroke
				(width 0.1524)
				(type default)
			)
			(layer "B.SilkS")
		)
		(fp_rect
			(start 0.508 0.9398)
			(end -0.508 -0.9398)
			(stroke
				(width 0)
				(type default)
			)
			(fill no)
			(layer "B.CrtYd")
		)
		(fp_rect
			(start 0.508 0.9398)
			(end -0.508 -0.9398)
			(stroke
				(width 0)
				(type default)
			)
			(fill no)
			(layer "B.Fab")
		)
		(pad "1" smd custom
			(at 0 -0.4445 180)
			(size 0.1397 0.1397)
			(layers "B.Cu" "B.Mask" "B.Paste")
			(net "BMC_SSD_RST#0_A1")
			(options
				(clearance outline)
				(anchor circle)
			)
			(primitives
				(gr_poly
					(pts
						(arc
							(start -0.1778 0.2794)
							(mid -0.249642 0.249642)
							(end -0.2794 0.1778)
						)
						(arc
							(start -0.2794 -0.1778)
							(mid -0.249642 -0.249642)
							(end -0.1778 -0.2794)
						)
						(arc
							(start 0.1778 -0.2794)
							(mid 0.249642 -0.249642)
							(end 0.2794 -0.1778)
						)
						(arc
							(start 0.2794 0.1778)
							(mid 0.249642 0.249642)
							(end 0.1778 0.2794)
						)
					)
					(width 0)
					(fill yes)
				)
			)
		)
		(pad "2" smd custom
			(at 0 0.4445 180)
			(size 0.1397 0.1397)
			(layers "B.Cu" "B.Mask" "B.Paste")
			(net "P3V3_STBY")
			(options
				(clearance outline)
				(anchor circle)
			)
			(primitives
				(gr_poly
					(pts
						(arc
							(start -0.1778 0.2794)
							(mid -0.249642 0.249642)
							(end -0.2794 0.1778)
						)
						(arc
							(start -0.2794 -0.1778)
							(mid -0.249642 -0.249642)
							(end -0.1778 -0.2794)
						)
						(arc
							(start 0.1778 -0.2794)
							(mid 0.249642 -0.249642)
							(end 0.2794 -0.1778)
						)
						(arc
							(start 0.2794 0.1778)
							(mid 0.249642 0.249642)
							(end 0.1778 0.2794)
						)
					)
					(width 0)
					(fill yes)
				)
			)
		)
	)
	(footprint ""
		(layer "B.Cu")
		(at 252.603 -50.004472 -90)
		(property "Reference" "C608"
			(at 0 0 90)
			(layer "B.SilkS")
			(hide yes)
			(effects
				(font
					(size 1.27 1.27)
				)
				(justify mirror)
			)
		)
		(property "Value" "SCD1U16V1KX-1-GP"
			(at 2.8321 -1.7399 270)
			(unlocked yes)
			(layer "B.Fab")
			(hide yes)
			(effects
				(font
					(size 1.016 1.016)
					(thickness 0.1524)
				)
				(justify mirror)
			)
		)
		(property "Device Type" "C0201H13"
			(at 2.8321 -3.2639 270)
			(unlocked yes)
			(layer "B.Fab")
			(hide yes)
			(effects
				(font
					(size 1.016 1.016)
					(thickness 0.1524)
				)
				(justify mirror)
			)
		)
		(duplicate_pad_numbers_are_jumpers no)
		(fp_rect
			(start 0.2794 0.6477)
			(end -0.2794 -0.6477)
			(stroke
				(width 0)
				(type default)
			)
			(fill no)
			(layer "B.CrtYd")
		)
		(fp_rect
			(start 0.2794 0.6477)
			(end -0.2794 -0.6477)
			(stroke
				(width 0)
				(type default)
			)
			(fill no)
			(layer "B.Fab")
		)
		(pad "1" smd custom
			(at 0 -0.2794 90)
			(size 0.0762 0.0762)
			(layers "B.Cu" "B.Mask" "B.Paste")
			(net "DUT_AVD_PCIE")
			(options
				(clearance outline)
				(anchor circle)
			)
			(primitives
				(gr_poly
					(pts
						(arc
							(start 0.1524 0.127)
							(mid 0.137521 0.162921)
							(end 0.1016 0.1778)
						)
						(arc
							(start -0.1016 0.1778)
							(mid -0.137521 0.162921)
							(end -0.1524 0.127)
						)
						(arc
							(start -0.1524 -0.127)
							(mid -0.137521 -0.162921)
							(end -0.1016 -0.1778)
						)
						(arc
							(start 0.1016 -0.1778)
							(mid 0.137521 -0.162921)
							(end 0.1524 -0.127)
						)
					)
					(width 0)
					(fill yes)
				)
			)
		)
		(pad "2" smd custom
			(at 0 0.2794 90)
			(size 0.0762 0.0762)
			(layers "B.Cu" "B.Mask" "B.Paste")
			(net "GND")
			(options
				(clearance outline)
				(anchor circle)
			)
			(primitives
				(gr_poly
					(pts
						(arc
							(start 0.1524 0.127)
							(mid 0.137521 0.162921)
							(end 0.1016 0.1778)
						)
						(arc
							(start -0.1016 0.1778)
							(mid -0.137521 0.162921)
							(end -0.1524 0.127)
						)
						(arc
							(start -0.1524 -0.127)
							(mid -0.137521 -0.162921)
							(end -0.1016 -0.1778)
						)
						(arc
							(start 0.1016 -0.1778)
							(mid 0.137521 -0.162921)
							(end 0.1524 -0.127)
						)
					)
					(width 0)
					(fill yes)
				)
			)
		)
	)
)
